#ISCELL
  pure_quanta quanta_title_block_c *
  *
#CELL
  pure_quanta lcmxo3lf2100c5bg256c *
  page40_i1
#ISCELL
  logical_power universal_gnd *
  page40_i2
#ISCELL
  logical_power universal_power *
  page40_i3
